# T6G (Grand Teton) — schematic netlist excerpt (pin names and nets, part order shuffled) for the footprints in the layout excerpt that follows; sources: Cadence DE-HDL packaged netlist, KiCad conversion of 04192023_DAF0TMB3IC0_F0TG_MB_C_brd_V02_OCP.brd

R6053  Q_RES  0 5% CHIP  pkg 0402LF  page 82 : A = M2_SSD0_CLKREQ_EN_N ; B = FM_CLKREQ_M2_1_N
R966  Q_RES  1K 1% EMPTY  pkg 0201LF  page 276 : A = P1V8_CPU0_RT_1D ; B = RT_CPU0_P0_ADDR2
C2269  Q_CAP  22UF 4V 20% X6S  pkg C0402  page 72 : A = PVDDCR_SOC_P1 ; B = GND

(kicad_pcb
	(version 20260206)
	(generator "pcbnew")
	(generator_version "10.0")
	(general
		(thickness 1.6)
		(legacy_teardrops no)
	)
	(paper "A4")
	(title_block
		(title "04192023_DAF0TMB3IC0_F0TG_MB_C_brd_V02_OCP.brd")
		(comment 1 "Grand Teton / footprints 477-479 of 8354")
	)
	(layers
		(0 "F.Cu" signal "TOP")
		(4 "In1.Cu" signal "GND")
		(6 "In2.Cu" signal "IN1")
		(8 "In3.Cu" signal "GND1")
		(10 "In4.Cu" signal "IN2")
		(12 "In5.Cu" signal "GND2")
		(14 "In6.Cu" signal "IN3")
		(16 "In7.Cu" signal "GND3")
		(18 "In8.Cu" signal "VCC")
		(20 "In9.Cu" signal "VCC1")
		(22 "In10.Cu" signal "GND4")
		(24 "In11.Cu" signal "IN4")
		(26 "In12.Cu" signal "GND5")
		(28 "In13.Cu" signal "IN5")
		(30 "In14.Cu" signal "GND6")
		(32 "In15.Cu" signal "IN6")
		(34 "In16.Cu" signal "GND7")
		(2 "B.Cu" signal "BOTTOM")
		(9 "F.Adhes" user "F.Adhesive")
		(11 "B.Adhes" user "B.Adhesive")
		(13 "F.Paste" user "Package Geometry/Pastemask Top")
		(15 "B.Paste" user "Package Geometry/Pastemask Bottom")
		(5 "F.SilkS" user "Ref Des/Silkscreen Top")
		(7 "B.SilkS" user "Ref Des/Silkscreen Bottom")
		(1 "F.Mask" user "Board Geometry/Soldermask Top")
		(3 "B.Mask" user "Board Geometry/Soldermask Bottom")
		(17 "Dwgs.User" user "User.Drawings")
		(19 "Cmts.User" user "User.Comments")
		(21 "Eco1.User" user "User.Eco1")
		(23 "Eco2.User" user "User.Eco2")
		(25 "Edge.Cuts" user "Board Geometry/Outline")
		(27 "Margin" user)
		(31 "F.CrtYd" user "Package Geometry/Place Bound Top")
		(29 "B.CrtYd" user "Package Geometry/Place Bound Bottom")
		(35 "F.Fab" user "Ref Des/Assembly Top")
		(33 "B.Fab" user "Ref Des/Assembly Bottom")
	)
	(footprint ""
		(layer "F.Cu")
		(at 117.895624 -259.355336 180)
		(property "Reference" "C2269"
			(at 0 0 180)
			(layer "F.SilkS")
			(hide yes)
			(effects
				(font
					(size 1.27 1.27)
				)
			)
		)
		(property "Value" ""
			(at 0 0 180)
			(layer "F.Fab")
			(effects
				(font
					(size 1.27 1.27)
				)
			)
		)
		(duplicate_pad_numbers_are_jumpers no)
		(fp_line
			(start 0.7874 0.4064)
			(end -0.7874 0.4064)
			(stroke
				(width 0.1524)
				(type default)
			)
			(layer "F.SilkS")
		)
		(fp_line
			(start 0.7874 -0.4064)
			(end 0.7874 0.4064)
			(stroke
				(width 0.1524)
				(type default)
			)
			(layer "F.SilkS")
		)
		(fp_line
			(start -0.7874 0.4064)
			(end -0.7874 -0.4064)
			(stroke
				(width 0.1524)
				(type default)
			)
			(layer "F.SilkS")
		)
		(fp_line
			(start -0.7874 -0.4064)
			(end 0.7874 -0.4064)
			(stroke
				(width 0.1524)
				(type default)
			)
			(layer "F.SilkS")
		)
		(fp_line
			(start 0.67945 0.3048)
			(end 0.120396 0.3048)
			(stroke
				(width 0.1)
				(type default)
			)
			(layer "F.Fab")
		)
		(fp_line
			(start 0.67945 -0.3048)
			(end 0.67945 0.3048)
			(stroke
				(width 0.1)
				(type default)
			)
			(layer "F.Fab")
		)
		(fp_line
			(start 0.12065 -0.2794)
			(end 0.12065 -0.3048)
			(stroke
				(width 0.1)
				(type default)
			)
			(layer "F.Fab")
		)
		(fp_line
			(start 0.12065 -0.3048)
			(end 0.67945 -0.3048)
			(stroke
				(width 0.1)
				(type default)
			)
			(layer "F.Fab")
		)
		(fp_line
			(start 0.120396 0.3048)
			(end 0.120396 0.2794)
			(stroke
				(width 0.1)
				(type default)
			)
			(layer "F.Fab")
		)
		(fp_line
			(start 0.120396 0.2794)
			(end -0.12065 0.2794)
			(stroke
				(width 0.1)
				(type default)
			)
			(layer "F.Fab")
		)
		(fp_line
			(start -0.12065 0.3048)
			(end -0.67945 0.3048)
			(stroke
				(width 0.1)
				(type default)
			)
			(layer "F.Fab")
		)
		(fp_line
			(start -0.12065 0.2794)
			(end -0.12065 0.3048)
			(stroke
				(width 0.1)
				(type default)
			)
			(layer "F.Fab")
		)
		(fp_line
			(start -0.12065 -0.2794)
			(end 0.12065 -0.2794)
			(stroke
				(width 0.1)
				(type default)
			)
			(layer "F.Fab")
		)
		(fp_line
			(start -0.12065 -0.305054)
			(end -0.12065 -0.2794)
			(stroke
				(width 0.1)
				(type default)
			)
			(layer "F.Fab")
		)
		(fp_line
			(start -0.67945 0.3048)
			(end -0.67945 -0.305054)
			(stroke
				(width 0.1)
				(type default)
			)
			(layer "F.Fab")
		)
		(fp_line
			(start -0.67945 -0.305054)
			(end -0.12065 -0.305054)
			(stroke
				(width 0.1)
				(type default)
			)
			(layer "F.Fab")
		)
		(pad "1" smd circle
			(at -0.40005 0 180)
			(size 0 0)
			(layers "F.Cu" "F.Mask" "F.Paste")
			(net "PVDDCR_SOC_P1")
		)
		(pad "2" smd circle
			(at 0.40005 0 180)
			(size 0 0)
			(layers "F.Cu" "F.Mask" "F.Paste")
			(net "GND")
		)
	)
	(footprint ""
		(layer "F.Cu")
		(at 328.694542 -393.9032 90)
		(property "Reference" "R966"
			(at 0 0 90)
			(layer "F.SilkS")
			(hide yes)
			(effects
				(font
					(size 1.27 1.27)
				)
			)
		)
		(property "Value" ""
			(at 0 0 90)
			(layer "F.Fab")
			(effects
				(font
					(size 1.27 1.27)
				)
			)
		)
		(duplicate_pad_numbers_are_jumpers no)
		(fp_line
			(start 0.32512 -0.175006)
			(end 0.32512 0.175006)
			(stroke
				(width 0.1)
				(type default)
			)
			(layer "F.Fab")
		)
		(fp_line
			(start -0.32512 -0.175006)
			(end 0.32512 -0.175006)
			(stroke
				(width 0.1)
				(type default)
			)
			(layer "F.Fab")
		)
		(fp_line
			(start 0.32512 0.175006)
			(end -0.32512 0.175006)
			(stroke
				(width 0.1)
				(type default)
			)
			(layer "F.Fab")
		)
		(fp_line
			(start -0.32512 0.175006)
			(end -0.32512 -0.175006)
			(stroke
				(width 0.1)
				(type default)
			)
			(layer "F.Fab")
		)
		(pad "1" smd rect
			(at -0.2667 0 90)
			(size 0.3048 0.381)
			(layers "F.Cu" "F.Mask" "F.Paste")
			(net "P1V8_CPU0_RT_1D")
		)
		(pad "2" smd rect
			(at 0.2667 0 270)
			(size 0.3048 0.381)
			(layers "F.Cu" "F.Mask" "F.Paste")
			(net "RT_CPU0_P0_ADDR2")
		)
	)
	(footprint ""
		(layer "F.Cu")
		(at 186.817 -100.294948 90)
		(property "Reference" "R6053"
			(at 0 0 90)
			(layer "F.SilkS")
			(hide yes)
			(effects
				(font
					(size 1.27 1.27)
				)
			)
		)
		(property "Value" ""
			(at 0 0 90)
			(layer "F.Fab")
			(effects
				(font
					(size 1.27 1.27)
				)
			)
		)
		(duplicate_pad_numbers_are_jumpers no)
		(fp_line
			(start 0.7874 -0.4064)
			(end 0.7874 0.4064)
			(stroke
				(width 0.1524)
				(type default)
			)
			(layer "F.SilkS")
		)
		(fp_line
			(start -0.7874 -0.4064)
			(end 0.7874 -0.4064)
			(stroke
				(width 0.1524)
				(type default)
			)
			(layer "F.SilkS")
		)
		(fp_line
			(start 0.7874 0.4064)
			(end -0.7874 0.4064)
			(stroke
				(width 0.1524)
				(type default)
			)
			(layer "F.SilkS")
		)
		(fp_line
			(start -0.7874 0.4064)
			(end -0.7874 -0.4064)
			(stroke
				(width 0.1524)
				(type default)
			)
			(layer "F.SilkS")
		)
		(fp_line
			(start -0.12065 -0.305054)
			(end -0.12065 -0.2794)
			(stroke
				(width 0.1)
				(type default)
			)
			(layer "F.Fab")
		)
		(fp_line
			(start -0.67945 -0.305054)
			(end -0.12065 -0.305054)
			(stroke
				(width 0.1)
				(type default)
			)
			(layer "F.Fab")
		)
		(fp_line
			(start 0.67945 -0.3048)
			(end 0.67945 0.3048)
			(stroke
				(width 0.1)
				(type default)
			)
			(layer "F.Fab")
		)
		(fp_line
			(start 0.12065 -0.3048)
			(end 0.67945 -0.3048)
			(stroke
				(width 0.1)
				(type default)
			)
			(layer "F.Fab")
		)
		(fp_line
			(start 0.12065 -0.2794)
			(end 0.12065 -0.3048)
			(stroke
				(width 0.1)
				(type default)
			)
			(layer "F.Fab")
		)
		(fp_line
			(start -0.12065 -0.2794)
			(end 0.12065 -0.2794)
			(stroke
				(width 0.1)
				(type default)
			)
			(layer "F.Fab")
		)
		(fp_line
			(start 0.120396 0.2794)
			(end -0.12065 0.2794)
			(stroke
				(width 0.1)
				(type default)
			)
			(layer "F.Fab")
		)
		(fp_line
			(start -0.12065 0.2794)
			(end -0.12065 0.3048)
			(stroke
				(width 0.1)
				(type default)
			)
			(layer "F.Fab")
		)
		(fp_line
			(start 0.67945 0.3048)
			(end 0.120396 0.3048)
			(stroke
				(width 0.1)
				(type default)
			)
			(layer "F.Fab")
		)
		(fp_line
			(start 0.120396 0.3048)
			(end 0.120396 0.2794)
			(stroke
				(width 0.1)
				(type default)
			)
			(layer "F.Fab")
		)
		(fp_line
			(start -0.12065 0.3048)
			(end -0.67945 0.3048)
			(stroke
				(width 0.1)
				(type default)
			)
			(layer "F.Fab")
		)
		(fp_line
			(start -0.67945 0.3048)
			(end -0.67945 -0.305054)
			(stroke
				(width 0.1)
				(type default)
			)
			(layer "F.Fab")
		)
		(pad "1" smd circle
			(at -0.40005 0 90)
			(size 0 0)
			(layers "F.Cu" "F.Mask" "F.Paste")
			(net "M2_SSD0_CLKREQ_EN_N")
		)
		(pad "2" smd circle
			(at 0.40005 0 90)
			(size 0 0)
			(layers "F.Cu" "F.Mask" "F.Paste")
			(net "FM_CLKREQ_M2_1_N")
		)
	)
)
